(kicad_pcb
	(version 20241229)
	(generator "pcbnew")
	(generator_version "9.0")
	(general
		(thickness 1.61)
		(legacy_teardrops no)
	)
	(paper "A3")
	(title_block
		(title "SO-DIMM DDR5 Tester")
		(date "2025-11-26")
		(rev "1.3.0")
		(comment 9 "footprints 504-509 of 627")
	)
	(layers
		(0 "F.Cu" signal)
		(4 "In1.Cu" power)
		(6 "In2.Cu" mixed)
		(8 "In3.Cu" power)
		(10 "In4.Cu" mixed)
		(12 "In5.Cu" power)
		(14 "In6.Cu" mixed)
		(16 "In7.Cu" power)
		(18 "In8.Cu" power)
		(20 "In9.Cu" mixed)
		(22 "In10.Cu" power)
		(2 "B.Cu" signal)
		(9 "F.Adhes" user "F.Adhesive")
		(11 "B.Adhes" user "B.Adhesive")
		(13 "F.Paste" user)
		(15 "B.Paste" user)
		(5 "F.SilkS" user "F.Silkscreen")
		(7 "B.SilkS" user "B.Silkscreen")
		(1 "F.Mask" user)
		(3 "B.Mask" user)
		(17 "Dwgs.User" user "User.Drawings")
		(19 "Cmts.User" user "User.Comments")
		(21 "Eco1.User" user "User.Eco1")
		(23 "Eco2.User" user "User.Eco2")
		(25 "Edge.Cuts" user)
		(27 "Margin" user)
		(31 "F.CrtYd" user "F.Courtyard")
		(29 "B.CrtYd" user "B.Courtyard")
		(35 "F.Fab" user)
		(33 "B.Fab" user)
	)
	(footprint "antmicro-footprints:C_0402_1005Metric"
		(layer "B.Cu")
		(at 140.875501 176.301)
		(descr "Capacitor SMD 0402 (1005 Metric), square (rectangular) end terminal, IPC_7351 nominal, (Body size source: IPC-SM-782 page 76, https://www.pcb-3d.com/wordpress/wp-content/uploads/ipc-sm-782a_amendment_1_and_2.pdf)")
		(tags "capacitor 0402")
		(property "Reference" "C84"
			(at 0 1.17 180)
			(layer "B.SilkS")
			(hide yes)
			(effects
				(font
					(size 0.7 0.7)
					(thickness 0.15)
				)
				(justify left bottom mirror)
			)
		)
		(property "Value" "C_100n_0402"
			(at 0 -1.169 180)
			(layer "B.Fab")
			(effects
				(font
					(size 0.7 0.7)
					(thickness 0.15)
				)
				(justify left bottom mirror)
			)
		)
		(property "Datasheet" "https://www.murata.com/products/productdetail?partno=GRM155R61H104KE14%23"
			(at 0 0 0)
			(layer "F.Fab")
			(hide yes)
			(effects
				(font
					(size 1.27 1.27)
					(thickness 0.15)
				)
			)
		)
		(property "Author" "Antmicro"
			(at 0 0 0)
			(layer "B.Fab")
			(hide yes)
			(effects
				(font
					(size 1 1)
					(thickness 0.15)
				)
				(justify mirror)
			)
		)
		(property "Dielectric" "X5R"
			(at 0 0 0)
			(layer "B.Fab")
			(hide yes)
			(effects
				(font
					(size 1 1)
					(thickness 0.15)
				)
				(justify mirror)
			)
		)
		(property "License" "Apache-2.0"
			(at 0 0 0)
			(layer "B.Fab")
			(hide yes)
			(effects
				(font
					(size 1 1)
					(thickness 0.15)
				)
				(justify mirror)
			)
		)
		(property "MPN" "GRM155R61H104KE14D"
			(at 0 0 0)
			(layer "B.Fab")
			(hide yes)
			(effects
				(font
					(size 1 1)
					(thickness 0.15)
				)
				(justify mirror)
			)
		)
		(property "Manufacturer" "Murata"
			(at 0 0 0)
			(layer "B.Fab")
			(hide yes)
			(effects
				(font
					(size 1 1)
					(thickness 0.15)
				)
				(justify mirror)
			)
		)
		(property "Val" "100n"
			(at 0 0 0)
			(layer "B.Fab")
			(hide yes)
			(effects
				(font
					(size 1 1)
					(thickness 0.15)
				)
				(justify mirror)
			)
		)
		(property "Voltage" "50V"
			(at 0 0 0)
			(layer "B.Fab")
			(hide yes)
			(effects
				(font
					(size 1 1)
					(thickness 0.15)
				)
				(justify mirror)
			)
		)
		(sheetname "/FPGA power/")
		(sheetfile "fpga-power.kicad_sch")
		(attr smd)
		(fp_rect
			(start -0.9656 0.4572)
			(end 0.9652 -0.4828)
			(stroke
				(width 0.05)
				(type solid)
			)
			(fill no)
			(layer "B.CrtYd")
		)
		(fp_line
			(start -0.5 -0.248)
			(end -0.5 0.25)
			(stroke
				(width 0.15)
				(type solid)
			)
			(layer "B.Fab")
		)
		(fp_line
			(start -0.5 0.25)
			(end 0.498 0.25)
			(stroke
				(width 0.15)
				(type solid)
			)
			(layer "B.Fab")
		)
		(fp_line
			(start 0.498 -0.248)
			(end -0.5 -0.248)
			(stroke
				(width 0.15)
				(type solid)
			)
			(layer "B.Fab")
		)
		(fp_line
			(start 0.498 0.25)
			(end 0.498 -0.248)
			(stroke
				(width 0.15)
				(type solid)
			)
			(layer "B.Fab")
		)
		(pad "1" smd roundrect
			(at -0.5 0 270)
			(size 0.6 0.6)
			(layers "B.Cu" "B.Mask" "B.Paste")
			(roundrect_rratio 0.25)
			(net 1 "GND")
			(pintype "passive")
		)
		(pad "2" smd roundrect
			(at 0.498 0)
			(size 0.6 0.6)
			(layers "B.Cu" "B.Mask" "B.Paste")
			(roundrect_rratio 0.25)
			(net 188 "+1V8")
			(pintype "passive")
		)
	)
	(footprint "antmicro-footprints:C_0402_1005Metric"
		(layer "B.Cu")
		(at 146.875501 164.301)
		(descr "Capacitor SMD 0402 (1005 Metric), square (rectangular) end terminal, IPC_7351 nominal, (Body size source: IPC-SM-782 page 76, https://www.pcb-3d.com/wordpress/wp-content/uploads/ipc-sm-782a_amendment_1_and_2.pdf)")
		(tags "capacitor 0402")
		(property "Reference" "C91"
			(at 0 1.17 180)
			(layer "B.SilkS")
			(hide yes)
			(effects
				(font
					(size 0.7 0.7)
					(thickness 0.15)
				)
				(justify left bottom mirror)
			)
		)
		(property "Value" "C_100n_0402"
			(at 0 -1.169 180)
			(layer "B.Fab")
			(effects
				(font
					(size 0.7 0.7)
					(thickness 0.15)
				)
				(justify left bottom mirror)
			)
		)
		(property "Datasheet" "https://www.murata.com/products/productdetail?partno=GRM155R61H104KE14%23"
			(at 0 0 0)
			(layer "F.Fab")
			(hide yes)
			(effects
				(font
					(size 1.27 1.27)
					(thickness 0.15)
				)
			)
		)
		(property "Author" "Antmicro"
			(at 0 0 0)
			(layer "B.Fab")
			(hide yes)
			(effects
				(font
					(size 1 1)
					(thickness 0.15)
				)
				(justify mirror)
			)
		)
		(property "Dielectric" "X5R"
			(at 0 0 0)
			(layer "B.Fab")
			(hide yes)
			(effects
				(font
					(size 1 1)
					(thickness 0.15)
				)
				(justify mirror)
			)
		)
		(property "License" "Apache-2.0"
			(at 0 0 0)
			(layer "B.Fab")
			(hide yes)
			(effects
				(font
					(size 1 1)
					(thickness 0.15)
				)
				(justify mirror)
			)
		)
		(property "MPN" "GRM155R61H104KE14D"
			(at 0 0 0)
			(layer "B.Fab")
			(hide yes)
			(effects
				(font
					(size 1 1)
					(thickness 0.15)
				)
				(justify mirror)
			)
		)
		(property "Manufacturer" "Murata"
			(at 0 0 0)
			(layer "B.Fab")
			(hide yes)
			(effects
				(font
					(size 1 1)
					(thickness 0.15)
				)
				(justify mirror)
			)
		)
		(property "Val" "100n"
			(at 0 0 0)
			(layer "B.Fab")
			(hide yes)
			(effects
				(font
					(size 1 1)
					(thickness 0.15)
				)
				(justify mirror)
			)
		)
		(property "Voltage" "50V"
			(at 0 0 0)
			(layer "B.Fab")
			(hide yes)
			(effects
				(font
					(size 1 1)
					(thickness 0.15)
				)
				(justify mirror)
			)
		)
		(sheetname "/FPGA power/")
		(sheetfile "fpga-power.kicad_sch")
		(attr smd)
		(fp_rect
			(start -0.9656 0.4572)
			(end 0.9652 -0.4828)
			(stroke
				(width 0.05)
				(type solid)
			)
			(fill no)
			(layer "B.CrtYd")
		)
		(fp_line
			(start -0.5 -0.248)
			(end -0.5 0.25)
			(stroke
				(width 0.15)
				(type solid)
			)
			(layer "B.Fab")
		)
		(fp_line
			(start -0.5 0.25)
			(end 0.498 0.25)
			(stroke
				(width 0.15)
				(type solid)
			)
			(layer "B.Fab")
		)
		(fp_line
			(start 0.498 -0.248)
			(end -0.5 -0.248)
			(stroke
				(width 0.15)
				(type solid)
			)
			(layer "B.Fab")
		)
		(fp_line
			(start 0.498 0.25)
			(end 0.498 -0.248)
			(stroke
				(width 0.15)
				(type solid)
			)
			(layer "B.Fab")
		)
		(pad "1" smd roundrect
			(at -0.5 0 270)
			(size 0.6 0.6)
			(layers "B.Cu" "B.Mask" "B.Paste")
			(roundrect_rratio 0.25)
			(net 1 "GND")
			(pintype "passive")
		)
		(pad "2" smd roundrect
			(at 0.498 0)
			(size 0.6 0.6)
			(layers "B.Cu" "B.Mask" "B.Paste")
			(roundrect_rratio 0.25)
			(net 206 "+1V1")
			(pintype "passive")
		)
	)
	(footprint "antmicro-footprints:C_0402_1005Metric"
		(layer "B.Cu")
		(at 198.065 147.301 -90)
		(descr "Capacitor SMD 0402")
		(tags "capacitor SMD 0402")
		(property "Reference" "C212"
			(at 0 0.699 90)
			(layer "B.SilkS")
			(hide yes)
			(effects
				(font
					(size 0.7 0.7)
					(thickness 0.15)
				)
				(justify left bottom mirror)
			)
		)
		(property "Value" "C_100n_0402"
			(at -1.022927 -2.155213 90)
			(layer "B.Fab")
			(effects
				(font
					(size 0.7 0.7)
					(thickness 0.15)
				)
				(justify left bottom mirror)
			)
		)
		(property "Datasheet" "https://www.murata.com/products/productdetail?partno=GRM155R61H104KE14%23"
			(at 0 0 270)
			(layer "F.Fab")
			(hide yes)
			(effects
				(font
					(size 1.27 1.27)
					(thickness 0.15)
				)
			)
		)
		(property "Author" "Antmicro"
			(at 50.764 345.366 0)
			(layer "B.Fab")
			(hide yes)
			(effects
				(font
					(size 1 1)
					(thickness 0.15)
				)
				(justify mirror)
			)
		)
		(property "Dielectric" "X5R"
			(at 50.764 345.366 0)
			(layer "B.Fab")
			(hide yes)
			(effects
				(font
					(size 1 1)
					(thickness 0.15)
				)
				(justify mirror)
			)
		)
		(property "License" "Apache-2.0"
			(at 50.764 345.366 0)
			(layer "B.Fab")
			(hide yes)
			(effects
				(font
					(size 1 1)
					(thickness 0.15)
				)
				(justify mirror)
			)
		)
		(property "MPN" "GRM155R61H104KE14D"
			(at 50.764 345.366 0)
			(layer "B.Fab")
			(hide yes)
			(effects
				(font
					(size 1 1)
					(thickness 0.15)
				)
				(justify mirror)
			)
		)
		(property "Manufacturer" "Murata"
			(at 50.764 345.366 0)
			(layer "B.Fab")
			(hide yes)
			(effects
				(font
					(size 1 1)
					(thickness 0.15)
				)
				(justify mirror)
			)
		)
		(property "Val" "100n"
			(at 50.764 345.366 0)
			(layer "B.Fab")
			(hide yes)
			(effects
				(font
					(size 1 1)
					(thickness 0.15)
				)
				(justify mirror)
			)
		)
		(property "Voltage" "50V"
			(at 50.764 345.366 0)
			(layer "B.Fab")
			(hide yes)
			(effects
				(font
					(size 1 1)
					(thickness 0.15)
				)
				(justify mirror)
			)
		)
		(sheetname "/Supply/")
		(sheetfile "supply.kicad_sch")
		(attr smd)
		(fp_rect
			(start -0.9659 0.481258)
			(end 0.9649 -0.458742)
			(stroke
				(width 0.05)
				(type solid)
			)
			(fill no)
			(layer "B.CrtYd")
		)
		(fp_line
			(start -0.499 0.25)
			(end 0.499 0.25)
			(stroke
				(width 0.15)
				(type solid)
			)
			(layer "B.Fab")
		)
		(fp_line
			(start 0.499 0.25)
			(end 0.499 -0.248)
			(stroke
				(width 0.15)
				(type solid)
			)
			(layer "B.Fab")
		)
		(fp_line
			(start -0.499 -0.248)
			(end -0.499 0.25)
			(stroke
				(width 0.15)
				(type solid)
			)
			(layer "B.Fab")
		)
		(fp_line
			(start 0.499 -0.248)
			(end -0.499 -0.248)
			(stroke
				(width 0.15)
				(type solid)
			)
			(layer "B.Fab")
		)
		(pad "1" smd roundrect
			(at -0.484 0 270)
			(size 0.59 0.64)
			(layers "B.Cu" "B.Mask" "B.Paste")
			(roundrect_rratio 0.25)
			(net 1 "GND")
			(pintype "passive")
		)
		(pad "2" smd roundrect
			(at 0.484 0 270)
			(size 0.59 0.64)
			(layers "B.Cu" "B.Mask" "B.Paste")
			(roundrect_rratio 0.25)
			(net 41 "+3V3_AON")
			(pintype "passive")
		)
	)
	(footprint "antmicro-footprints:C_0402_1005Metric"
		(layer "B.Cu")
		(at 136.375501 165.801 90)
		(descr "Capacitor SMD 0402 (1005 Metric), square (rectangular) end terminal, IPC_7351 nominal, (Body size source: IPC-SM-782 page 76, https://www.pcb-3d.com/wordpress/wp-content/uploads/ipc-sm-782a_amendment_1_and_2.pdf)")
		(tags "capacitor 0402")
		(property "Reference" "C37"
			(at 0 1.17 270)
			(layer "B.SilkS")
			(hide yes)
			(effects
				(font
					(size 0.7 0.7)
					(thickness 0.15)
				)
				(justify left bottom mirror)
			)
		)
		(property "Value" "C_100n_0402"
			(at 0 -1.169 270)
			(layer "B.Fab")
			(effects
				(font
					(size 0.7 0.7)
					(thickness 0.15)
				)
				(justify left bottom mirror)
			)
		)
		(property "Datasheet" "https://www.murata.com/products/productdetail?partno=GRM155R61H104KE14%23"
			(at 0 0 90)
			(layer "F.Fab")
			(hide yes)
			(effects
				(font
					(size 1.27 1.27)
					(thickness 0.15)
				)
			)
		)
		(property "Author" "Antmicro"
			(at 302.176501 29.425499 0)
			(layer "B.Fab")
			(hide yes)
			(effects
				(font
					(size 1 1)
					(thickness 0.15)
				)
				(justify mirror)
			)
		)
		(property "Dielectric" "X5R"
			(at 302.176501 29.425499 0)
			(layer "B.Fab")
			(hide yes)
			(effects
				(font
					(size 1 1)
					(thickness 0.15)
				)
				(justify mirror)
			)
		)
		(property "License" "Apache-2.0"
			(at 302.176501 29.425499 0)
			(layer "B.Fab")
			(hide yes)
			(effects
				(font
					(size 1 1)
					(thickness 0.15)
				)
				(justify mirror)
			)
		)
		(property "MPN" "GRM155R61H104KE14D"
			(at 302.176501 29.425499 0)
			(layer "B.Fab")
			(hide yes)
			(effects
				(font
					(size 1 1)
					(thickness 0.15)
				)
				(justify mirror)
			)
		)
		(property "Manufacturer" "Murata"
			(at 302.176501 29.425499 0)
			(layer "B.Fab")
			(hide yes)
			(effects
				(font
					(size 1 1)
					(thickness 0.15)
				)
				(justify mirror)
			)
		)
		(property "Val" "100n"
			(at 302.176501 29.425499 0)
			(layer "B.Fab")
			(hide yes)
			(effects
				(font
					(size 1 1)
					(thickness 0.15)
				)
				(justify mirror)
			)
		)
		(property "Voltage" "50V"
			(at 302.176501 29.425499 0)
			(layer "B.Fab")
			(hide yes)
			(effects
				(font
					(size 1 1)
					(thickness 0.15)
				)
				(justify mirror)
			)
		)
		(sheetname "/FPGA power/")
		(sheetfile "fpga-power.kicad_sch")
		(attr smd)
		(fp_rect
			(start -0.9656 0.4572)
			(end 0.9652 -0.4828)
			(stroke
				(width 0.05)
				(type solid)
			)
			(fill no)
			(layer "B.CrtYd")
		)
		(fp_line
			(start 0.498 -0.248)
			(end -0.5 -0.248)
			(stroke
				(width 0.15)
				(type solid)
			)
			(layer "B.Fab")
		)
		(fp_line
			(start -0.5 -0.248)
			(end -0.5 0.25)
			(stroke
				(width 0.15)
				(type solid)
			)
			(layer "B.Fab")
		)
		(fp_line
			(start 0.498 0.25)
			(end 0.498 -0.248)
			(stroke
				(width 0.15)
				(type solid)
			)
			(layer "B.Fab")
		)
		(fp_line
			(start -0.5 0.25)
			(end 0.498 0.25)
			(stroke
				(width 0.15)
				(type solid)
			)
			(layer "B.Fab")
		)
		(pad "1" smd roundrect
			(at -0.5 0)
			(size 0.6 0.6)
			(layers "B.Cu" "B.Mask" "B.Paste")
			(roundrect_rratio 0.25)
			(net 1 "GND")
			(pintype "passive")
		)
		(pad "2" smd roundrect
			(at 0.498 0 90)
			(size 0.6 0.6)
			(layers "B.Cu" "B.Mask" "B.Paste")
			(roundrect_rratio 0.25)
			(net 206 "+1V1")
			(pintype "passive")
		)
	)
	(footprint "antmicro-footprints:TP_SMD_1mm"
		(layer "B.Cu")
		(at 92.5 188.275 180)
		(property "Reference" "TP45"
			(at 0.9 -0.325 0)
			(layer "B.SilkS")
			(effects
				(font
					(size 0.7 0.7)
					(thickness 0.15)
				)
				(justify left bottom mirror)
			)
		)
		(property "Value" "TP_1mm_SMD"
			(at 0 -1.4 0)
			(layer "B.Fab")
			(effects
				(font
					(size 0.7 0.7)
					(thickness 0.15)
				)
				(justify left bottom mirror)
			)
		)
		(property "MPN" ""
			(at 0 0 0)
			(unlocked yes)
			(layer "B.Fab")
			(hide yes)
			(effects
				(font
					(size 1 1)
					(thickness 0.15)
				)
				(justify mirror)
			)
		)
		(property "Manufacturer" ""
			(at 0 0 0)
			(unlocked yes)
			(layer "B.Fab")
			(hide yes)
			(effects
				(font
					(size 1 1)
					(thickness 0.15)
				)
				(justify mirror)
			)
		)
		(property "Author" "Antmicro"
			(at 0 0 0)
			(unlocked yes)
			(layer "B.Fab")
			(hide yes)
			(effects
				(font
					(size 1 1)
					(thickness 0.15)
				)
				(justify mirror)
			)
		)
		(property "License" "Apache-2.0"
			(at 0 0 0)
			(unlocked yes)
			(layer "B.Fab")
			(hide yes)
			(effects
				(font
					(size 1 1)
					(thickness 0.15)
				)
				(justify mirror)
			)
		)
		(sheetname "/Debug FTDI/")
		(sheetfile "debug-ftdi.kicad_sch")
		(attr exclude_from_pos_files)
		(fp_circle
			(center 0 0)
			(end 0.6 0)
			(stroke
				(width 0.05)
				(type default)
			)
			(fill no)
			(layer "B.CrtYd")
		)
		(fp_text user "License: Apache-2.0"
			(at -0.5 -5.2 0)
			(layer "B.Fab")
			(effects
				(font
					(size 0.7 0.7)
					(thickness 0.15)
				)
				(justify left bottom mirror)
			)
		)
		(fp_text user "Author: Antmicro"
			(at -0.5 -4 0)
			(layer "B.Fab")
			(effects
				(font
					(size 0.7 0.7)
					(thickness 0.15)
				)
				(justify left bottom mirror)
			)
		)
		(fp_text user "${REFERENCE}"
			(at -0.5 -2.8 0)
			(layer "B.Fab")
			(effects
				(font
					(size 0.7 0.7)
					(thickness 0.15)
				)
				(justify left bottom mirror)
			)
		)
		(pad "1" smd circle
			(at 0 0 180)
			(size 1 1)
			(layers "B.Cu" "B.Mask")
			(net 47 "/Debug FTDI/JTAG.TDO")
			(pinfunction "1")
			(pintype "passive")
		)
	)
	(footprint "antmicro-footprints:C_0402_1005Metric"
		(layer "B.Cu")
		(at 149.377001 186.1505 180)
		(descr "Capacitor SMD 0402 (1005 Metric), square (rectangular) end terminal, IPC_7351 nominal, (Body size source: IPC-SM-782 page 76, https://www.pcb-3d.com/wordpress/wp-content/uploads/ipc-sm-782a_amendment_1_and_2.pdf)")
		(tags "capacitor 0402")
		(property "Reference" "C103"
			(at 0 1.17 0)
			(layer "B.SilkS")
			(hide yes)
			(effects
				(font
					(size 0.7 0.7)
					(thickness 0.15)
				)
				(justify left bottom mirror)
			)
		)
		(property "Value" "C_4u7_0402"
			(at 0 -1.169 0)
			(layer "B.Fab")
			(effects
				(font
					(size 0.7 0.7)
					(thickness 0.15)
				)
				(justify left bottom mirror)
			)
		)
		(property "Datasheet" "https://www.murata.com/products/productdetail?partno=GRM155R61A475MEAA%23"
			(at 0 0 180)
			(layer "F.Fab")
			(hide yes)
			(effects
				(font
					(size 1.27 1.27)
					(thickness 0.15)
				)
			)
		)
		(property "Author" "Antmicro"
			(at 298.754002 372.301 0)
			(layer "B.Fab")
			(hide yes)
			(effects
				(font
					(size 1 1)
					(thickness 0.15)
				)
				(justify mirror)
			)
		)
		(property "Dielectric" ""
			(at 298.754002 372.301 0)
			(layer "B.Fab")
			(hide yes)
			(effects
				(font
					(size 1 1)
					(thickness 0.15)
				)
				(justify mirror)
			)
		)
		(property "License" "Apache-2.0"
			(at 298.754002 372.301 0)
			(layer "B.Fab")
			(hide yes)
			(effects
				(font
					(size 1 1)
					(thickness 0.15)
				)
				(justify mirror)
			)
		)
		(property "MPN" "GRM155R61A475MEAAD"
			(at 298.754002 372.301 0)
			(layer "B.Fab")
			(hide yes)
			(effects
				(font
					(size 1 1)
					(thickness 0.15)
				)
				(justify mirror)
			)
		)
		(property "Manufacturer" "Murata"
			(at 298.754002 372.301 0)
			(layer "B.Fab")
			(hide yes)
			(effects
				(font
					(size 1 1)
					(thickness 0.15)
				)
				(justify mirror)
			)
		)
		(property "Val" "4u7"
			(at 298.754002 372.301 0)
			(layer "B.Fab")
			(hide yes)
			(effects
				(font
					(size 1 1)
					(thickness 0.15)
				)
				(justify mirror)
			)
		)
		(property "Voltage" ""
			(at 298.754002 372.301 0)
			(layer "B.Fab")
			(hide yes)
			(effects
				(font
					(size 1 1)
					(thickness 0.15)
				)
				(justify mirror)
			)
		)
		(sheetname "/FPGA power/")
		(sheetfile "fpga-power.kicad_sch")
		(attr smd)
		(fp_rect
			(start -0.9656 0.4572)
			(end 0.9652 -0.4828)
			(stroke
				(width 0.05)
				(type solid)
			)
			(fill no)
			(layer "B.CrtYd")
		)
		(fp_line
			(start 0.498 0.25)
			(end 0.498 -0.248)
			(stroke
				(width 0.15)
				(type solid)
			)
			(layer "B.Fab")
		)
		(fp_line
			(start 0.498 -0.248)
			(end -0.5 -0.248)
			(stroke
				(width 0.15)
				(type solid)
			)
			(layer "B.Fab")
		)
		(fp_line
			(start -0.5 0.25)
			(end 0.498 0.25)
			(stroke
				(width 0.15)
				(type solid)
			)
			(layer "B.Fab")
		)
		(fp_line
			(start -0.5 -0.248)
			(end -0.5 0.25)
			(stroke
				(width 0.15)
				(type solid)
			)
			(layer "B.Fab")
		)
		(pad "1" smd roundrect
			(at -0.5 0 90)
			(size 0.6 0.6)
			(layers "B.Cu" "B.Mask" "B.Paste")
			(roundrect_rratio 0.25)
			(net 226 "+1V2_MGTAVTT")
			(pintype "passive")
		)
		(pad "2" smd roundrect
			(at 0.498 0 180)
			(size 0.6 0.6)
			(layers "B.Cu" "B.Mask" "B.Paste")
			(roundrect_rratio 0.25)
			(net 1 "GND")
			(pintype "passive")
		)
	)
)
